(kicad_pcb
	(version 20260206)
	(generator "pcbnew")
	(generator_version "10.0")
	(general
		(thickness 1.6)
		(legacy_teardrops no)
	)
	(paper "A4")
	(title_block
		(title "04192023_DAF0TMB3IC0_F0TG_MB_C_brd_V02_OCP.brd")
		(comment 1 "Grand Teton / footprints 4935-4940 of 8354")
	)
	(layers
		(0 "F.Cu" signal "TOP")
		(4 "In1.Cu" signal "GND")
		(6 "In2.Cu" signal "IN1")
		(8 "In3.Cu" signal "GND1")
		(10 "In4.Cu" signal "IN2")
		(12 "In5.Cu" signal "GND2")
		(14 "In6.Cu" signal "IN3")
		(16 "In7.Cu" signal "GND3")
		(18 "In8.Cu" signal "VCC")
		(20 "In9.Cu" signal "VCC1")
		(22 "In10.Cu" signal "GND4")
		(24 "In11.Cu" signal "IN4")
		(26 "In12.Cu" signal "GND5")
		(28 "In13.Cu" signal "IN5")
		(30 "In14.Cu" signal "GND6")
		(32 "In15.Cu" signal "IN6")
		(34 "In16.Cu" signal "GND7")
		(2 "B.Cu" signal "BOTTOM")
		(9 "F.Adhes" user "F.Adhesive")
		(11 "B.Adhes" user "B.Adhesive")
		(13 "F.Paste" user "Package Geometry/Pastemask Top")
		(15 "B.Paste" user "Package Geometry/Pastemask Bottom")
		(5 "F.SilkS" user "Ref Des/Silkscreen Top")
		(7 "B.SilkS" user "Ref Des/Silkscreen Bottom")
		(1 "F.Mask" user "Board Geometry/Soldermask Top")
		(3 "B.Mask" user "Board Geometry/Soldermask Bottom")
		(17 "Dwgs.User" user "User.Drawings")
		(19 "Cmts.User" user "User.Comments")
		(21 "Eco1.User" user "User.Eco1")
		(23 "Eco2.User" user "User.Eco2")
		(25 "Edge.Cuts" user "Board Geometry/Outline")
		(27 "Margin" user)
		(31 "F.CrtYd" user "Package Geometry/Place Bound Top")
		(29 "B.CrtYd" user "Package Geometry/Place Bound Bottom")
		(35 "F.Fab" user "Ref Des/Assembly Top")
		(33 "B.Fab" user "Ref Des/Assembly Bottom")
	)
	(footprint ""
		(layer "B.Cu")
		(at 213.617302 -328.110088)
		(property "Reference" "R1242"
			(at 0 0 0)
			(layer "B.SilkS")
			(hide yes)
			(effects
				(font
					(size 1.27 1.27)
				)
				(justify mirror)
			)
		)
		(property "Value" ""
			(at 0 0 0)
			(layer "B.Fab")
			(effects
				(font
					(size 1.27 1.27)
				)
				(justify mirror)
			)
		)
		(duplicate_pad_numbers_are_jumpers no)
		(fp_line
			(start -0.7874 -0.4064)
			(end -0.7874 0.4064)
			(stroke
				(width 0.1524)
				(type default)
			)
			(layer "B.SilkS")
		)
		(fp_line
			(start -0.7874 0.4064)
			(end 0.7874 0.4064)
			(stroke
				(width 0.1524)
				(type default)
			)
			(layer "B.SilkS")
		)
		(fp_line
			(start 0.7874 -0.4064)
			(end -0.7874 -0.4064)
			(stroke
				(width 0.1524)
				(type default)
			)
			(layer "B.SilkS")
		)
		(fp_line
			(start 0.7874 0.4064)
			(end 0.7874 -0.4064)
			(stroke
				(width 0.1524)
				(type default)
			)
			(layer "B.SilkS")
		)
		(fp_line
			(start -0.67945 -0.3048)
			(end -0.67945 0.3048)
			(stroke
				(width 0.1)
				(type default)
			)
			(layer "B.Fab")
		)
		(fp_line
			(start -0.67945 0.3048)
			(end -0.120396 0.3048)
			(stroke
				(width 0.1)
				(type default)
			)
			(layer "B.Fab")
		)
		(fp_line
			(start -0.12065 -0.3048)
			(end -0.67945 -0.3048)
			(stroke
				(width 0.1)
				(type default)
			)
			(layer "B.Fab")
		)
		(fp_line
			(start -0.12065 -0.2794)
			(end -0.12065 -0.3048)
			(stroke
				(width 0.1)
				(type default)
			)
			(layer "B.Fab")
		)
		(fp_line
			(start -0.120396 0.2794)
			(end 0.12065 0.2794)
			(stroke
				(width 0.1)
				(type default)
			)
			(layer "B.Fab")
		)
		(fp_line
			(start -0.120396 0.3048)
			(end -0.120396 0.2794)
			(stroke
				(width 0.1)
				(type default)
			)
			(layer "B.Fab")
		)
		(fp_line
			(start 0.12065 -0.305054)
			(end 0.12065 -0.2794)
			(stroke
				(width 0.1)
				(type default)
			)
			(layer "B.Fab")
		)
		(fp_line
			(start 0.12065 -0.2794)
			(end -0.12065 -0.2794)
			(stroke
				(width 0.1)
				(type default)
			)
			(layer "B.Fab")
		)
		(fp_line
			(start 0.12065 0.2794)
			(end 0.12065 0.3048)
			(stroke
				(width 0.1)
				(type default)
			)
			(layer "B.Fab")
		)
		(fp_line
			(start 0.12065 0.3048)
			(end 0.67945 0.3048)
			(stroke
				(width 0.1)
				(type default)
			)
			(layer "B.Fab")
		)
		(fp_line
			(start 0.67945 -0.305054)
			(end 0.12065 -0.305054)
			(stroke
				(width 0.1)
				(type default)
			)
			(layer "B.Fab")
		)
		(fp_line
			(start 0.67945 0.3048)
			(end 0.67945 -0.305054)
			(stroke
				(width 0.1)
				(type default)
			)
			(layer "B.Fab")
		)
		(pad "1" smd circle
			(at 0.40005 0 180)
			(size 0 0)
			(layers "B.Cu" "B.Mask" "B.Paste")
			(net "ADC128_2_A0")
		)
		(pad "2" smd circle
			(at -0.40005 0 180)
			(size 0 0)
			(layers "B.Cu" "B.Mask" "B.Paste")
			(net "GND")
		)
	)
	(footprint ""
		(layer "B.Cu")
		(at 87.246206 -388.011162 -90)
		(property "Reference" "C204"
			(at 0 0 90)
			(layer "B.SilkS")
			(hide yes)
			(effects
				(font
					(size 1.27 1.27)
				)
				(justify mirror)
			)
		)
		(property "Value" ""
			(at 0 0 90)
			(layer "B.Fab")
			(effects
				(font
					(size 1.27 1.27)
				)
				(justify mirror)
			)
		)
		(duplicate_pad_numbers_are_jumpers no)
		(fp_line
			(start -0.299974 0.150114)
			(end 0.299974 0.150114)
			(stroke
				(width 0.1)
				(type default)
			)
			(layer "B.Fab")
		)
		(fp_line
			(start 0.299974 0.150114)
			(end 0.299974 -0.150114)
			(stroke
				(width 0.1)
				(type default)
			)
			(layer "B.Fab")
		)
		(fp_line
			(start -0.299974 -0.150114)
			(end -0.299974 0.150114)
			(stroke
				(width 0.1)
				(type default)
			)
			(layer "B.Fab")
		)
		(fp_line
			(start 0.299974 -0.150114)
			(end -0.299974 -0.150114)
			(stroke
				(width 0.1)
				(type default)
			)
			(layer "B.Fab")
		)
		(pad "1" smd rect
			(at 0.2667 0 90)
			(size 0.3048 0.381)
			(layers "B.Cu" "B.Mask" "B.Paste")
			(net "P1V8_CPU1_RT1_1A")
		)
		(pad "2" smd rect
			(at -0.2667 0 90)
			(size 0.3048 0.381)
			(layers "B.Cu" "B.Mask" "B.Paste")
			(net "GND")
		)
	)
	(footprint ""
		(layer "B.Cu")
		(at 361.391454 -246.44731 -60)
		(property "Reference" "C2171"
			(at 0 0 120)
			(layer "B.SilkS")
			(hide yes)
			(effects
				(font
					(size 1.27 1.27)
				)
				(justify mirror)
			)
		)
		(property "Value" ""
			(at 0 0 120)
			(layer "B.Fab")
			(effects
				(font
					(size 1.27 1.27)
				)
				(justify mirror)
			)
		)
		(duplicate_pad_numbers_are_jumpers no)
		(fp_line
			(start -0.787516 0.406438)
			(end 0.787425 0.40652)
			(stroke
				(width 0.1524)
				(type default)
			)
			(layer "B.SilkS")
		)
		(fp_line
			(start -0.787425 -0.40652)
			(end -0.787516 0.406438)
			(stroke
				(width 0.1524)
				(type default)
			)
			(layer "B.SilkS")
		)
		(fp_line
			(start 0.787425 0.40652)
			(end 0.787516 -0.406438)
			(stroke
				(width 0.1524)
				(type default)
			)
			(layer "B.SilkS")
		)
		(fp_line
			(start 0.787516 -0.406438)
			(end -0.787425 -0.40652)
			(stroke
				(width 0.1524)
				(type default)
			)
			(layer "B.SilkS")
		)
		(fp_line
			(start -0.679568 0.304811)
			(end -0.120258 0.304812)
			(stroke
				(width 0.1)
				(type default)
			)
			(layer "B.Fab")
		)
		(fp_line
			(start -0.120258 0.304812)
			(end -0.120334 0.279545)
			(stroke
				(width 0.1)
				(type default)
			)
			(layer "B.Fab")
		)
		(fp_line
			(start -0.120334 0.279545)
			(end 0.120587 0.279326)
			(stroke
				(width 0.1)
				(type default)
			)
			(layer "B.Fab")
		)
		(fp_line
			(start 0.120536 0.304813)
			(end 0.6795 0.304908)
			(stroke
				(width 0.1)
				(type default)
			)
			(layer "B.Fab")
		)
		(fp_line
			(start 0.120587 0.279326)
			(end 0.120536 0.304813)
			(stroke
				(width 0.1)
				(type default)
			)
			(layer "B.Fab")
		)
		(fp_line
			(start -0.6795 -0.304908)
			(end -0.679568 0.304811)
			(stroke
				(width 0.1)
				(type default)
			)
			(layer "B.Fab")
		)
		(fp_line
			(start 0.6795 0.304908)
			(end 0.679475 -0.305158)
			(stroke
				(width 0.1)
				(type default)
			)
			(layer "B.Fab")
		)
		(fp_line
			(start -0.120587 -0.279326)
			(end -0.120536 -0.304813)
			(stroke
				(width 0.1)
				(type default)
			)
			(layer "B.Fab")
		)
		(fp_line
			(start -0.120536 -0.304813)
			(end -0.6795 -0.304908)
			(stroke
				(width 0.1)
				(type default)
			)
			(layer "B.Fab")
		)
		(fp_line
			(start 0.120554 -0.279418)
			(end -0.120587 -0.279326)
			(stroke
				(width 0.1)
				(type default)
			)
			(layer "B.Fab")
		)
		(fp_line
			(start 0.120732 -0.305125)
			(end 0.120554 -0.279418)
			(stroke
				(width 0.1)
				(type default)
			)
			(layer "B.Fab")
		)
		(fp_line
			(start 0.679475 -0.305158)
			(end 0.120732 -0.305125)
			(stroke
				(width 0.1)
				(type default)
			)
			(layer "B.Fab")
		)
		(pad "1" smd circle
			(at 0.40005 0 120)
			(size 0 0)
			(layers "B.Cu" "B.Mask" "B.Paste")
			(net "PVDDCR_CPU0_P0")
		)
		(pad "2" smd circle
			(at -0.40005 0 120)
			(size 0 0)
			(layers "B.Cu" "B.Mask" "B.Paste")
			(net "GND")
		)
	)
	(footprint ""
		(layer "B.Cu")
		(at 276.436582 -193.99631)
		(property "Reference" "C104"
			(at 0 0 0)
			(layer "B.SilkS")
			(hide yes)
			(effects
				(font
					(size 1.27 1.27)
				)
				(justify mirror)
			)
		)
		(property "Value" ""
			(at 0 0 0)
			(layer "B.Fab")
			(effects
				(font
					(size 1.27 1.27)
				)
				(justify mirror)
			)
		)
		(duplicate_pad_numbers_are_jumpers no)
		(fp_line
			(start -0.7874 -0.4064)
			(end -0.7874 0.4064)
			(stroke
				(width 0.1524)
				(type default)
			)
			(layer "B.SilkS")
		)
		(fp_line
			(start -0.7874 0.4064)
			(end 0.7874 0.4064)
			(stroke
				(width 0.1524)
				(type default)
			)
			(layer "B.SilkS")
		)
		(fp_line
			(start 0.7874 -0.4064)
			(end -0.7874 -0.4064)
			(stroke
				(width 0.1524)
				(type default)
			)
			(layer "B.SilkS")
		)
		(fp_line
			(start 0.7874 0.4064)
			(end 0.7874 -0.4064)
			(stroke
				(width 0.1524)
				(type default)
			)
			(layer "B.SilkS")
		)
		(fp_line
			(start -0.67945 -0.3048)
			(end -0.67945 0.3048)
			(stroke
				(width 0.1)
				(type default)
			)
			(layer "B.Fab")
		)
		(fp_line
			(start -0.67945 0.3048)
			(end -0.120396 0.3048)
			(stroke
				(width 0.1)
				(type default)
			)
			(layer "B.Fab")
		)
		(fp_line
			(start -0.12065 -0.3048)
			(end -0.67945 -0.3048)
			(stroke
				(width 0.1)
				(type default)
			)
			(layer "B.Fab")
		)
		(fp_line
			(start -0.12065 -0.2794)
			(end -0.12065 -0.3048)
			(stroke
				(width 0.1)
				(type default)
			)
			(layer "B.Fab")
		)
		(fp_line
			(start -0.120396 0.2794)
			(end 0.12065 0.2794)
			(stroke
				(width 0.1)
				(type default)
			)
			(layer "B.Fab")
		)
		(fp_line
			(start -0.120396 0.3048)
			(end -0.120396 0.2794)
			(stroke
				(width 0.1)
				(type default)
			)
			(layer "B.Fab")
		)
		(fp_line
			(start 0.12065 -0.305054)
			(end 0.12065 -0.2794)
			(stroke
				(width 0.1)
				(type default)
			)
			(layer "B.Fab")
		)
		(fp_line
			(start 0.12065 -0.2794)
			(end -0.12065 -0.2794)
			(stroke
				(width 0.1)
				(type default)
			)
			(layer "B.Fab")
		)
		(fp_line
			(start 0.12065 0.2794)
			(end 0.12065 0.3048)
			(stroke
				(width 0.1)
				(type default)
			)
			(layer "B.Fab")
		)
		(fp_line
			(start 0.12065 0.3048)
			(end 0.67945 0.3048)
			(stroke
				(width 0.1)
				(type default)
			)
			(layer "B.Fab")
		)
		(fp_line
			(start 0.67945 -0.305054)
			(end 0.12065 -0.305054)
			(stroke
				(width 0.1)
				(type default)
			)
			(layer "B.Fab")
		)
		(fp_line
			(start 0.67945 0.3048)
			(end 0.67945 -0.305054)
			(stroke
				(width 0.1)
				(type default)
			)
			(layer "B.Fab")
		)
		(pad "1" smd circle
			(at 0.40005 0 180)
			(size 0 0)
			(layers "B.Cu" "B.Mask" "B.Paste")
			(net "P3V3_AUX")
		)
		(pad "2" smd circle
			(at -0.40005 0 180)
			(size 0 0)
			(layers "B.Cu" "B.Mask" "B.Paste")
			(net "GND")
		)
	)
	(footprint ""
		(layer "B.Cu")
		(at 95.506286 -386.766562 90)
		(property "Reference" "C307"
			(at 0 0 90)
			(layer "B.SilkS")
			(hide yes)
			(effects
				(font
					(size 1.27 1.27)
				)
				(justify mirror)
			)
		)
		(property "Value" ""
			(at 0 0 90)
			(layer "B.Fab")
			(effects
				(font
					(size 1.27 1.27)
				)
				(justify mirror)
			)
		)
		(duplicate_pad_numbers_are_jumpers no)
		(fp_line
			(start 0.299974 -0.150114)
			(end -0.299974 -0.150114)
			(stroke
				(width 0.1)
				(type default)
			)
			(layer "B.Fab")
		)
		(fp_line
			(start -0.299974 -0.150114)
			(end -0.299974 0.150114)
			(stroke
				(width 0.1)
				(type default)
			)
			(layer "B.Fab")
		)
		(fp_line
			(start 0.299974 0.150114)
			(end 0.299974 -0.150114)
			(stroke
				(width 0.1)
				(type default)
			)
			(layer "B.Fab")
		)
		(fp_line
			(start -0.299974 0.150114)
			(end 0.299974 0.150114)
			(stroke
				(width 0.1)
				(type default)
			)
			(layer "B.Fab")
		)
		(pad "1" smd rect
			(at 0.2667 0 270)
			(size 0.3048 0.381)
			(layers "B.Cu" "B.Mask" "B.Paste")
			(net "P0V9_CPU1_RT1_2A")
		)
		(pad "2" smd rect
			(at -0.2667 0 270)
			(size 0.3048 0.381)
			(layers "B.Cu" "B.Mask" "B.Paste")
			(net "GND")
		)
	)
	(footprint ""
		(layer "B.Cu")
		(at 64.911732 -338.086954 -90)
		(property "Reference" "PC418_4"
			(at 0 0 90)
			(layer "B.SilkS")
			(hide yes)
			(effects
				(font
					(size 1.27 1.27)
				)
				(justify mirror)
			)
		)
		(property "Value" ""
			(at 0 0 90)
			(layer "B.Fab")
			(effects
				(font
					(size 1.27 1.27)
				)
				(justify mirror)
			)
		)
		(duplicate_pad_numbers_are_jumpers no)
		(fp_line
			(start -1.524 0.762)
			(end 1.524 0.762)
			(stroke
				(width 0.1524)
				(type default)
			)
			(layer "B.SilkS")
		)
		(fp_line
			(start 1.524 0.762)
			(end 1.524 -0.762)
			(stroke
				(width 0.1524)
				(type default)
			)
			(layer "B.SilkS")
		)
		(fp_line
			(start -1.524 -0.762)
			(end -1.524 0.762)
			(stroke
				(width 0.1524)
				(type default)
			)
			(layer "B.SilkS")
		)
		(fp_line
			(start 1.524 -0.762)
			(end -1.524 -0.762)
			(stroke
				(width 0.1524)
				(type default)
			)
			(layer "B.SilkS")
		)
		(fp_line
			(start -1.1049 0.724916)
			(end -1.1049 -0.724916)
			(stroke
				(width 0.1)
				(type default)
			)
			(layer "B.Fab")
		)
		(fp_line
			(start 1.1049 0.724916)
			(end -1.1049 0.724916)
			(stroke
				(width 0.1)
				(type default)
			)
			(layer "B.Fab")
		)
		(fp_line
			(start -1.1049 -0.724916)
			(end 1.1049 -0.724916)
			(stroke
				(width 0.1)
				(type default)
			)
			(layer "B.Fab")
		)
		(fp_line
			(start 1.1049 -0.724916)
			(end 1.1049 0.724916)
			(stroke
				(width 0.1)
				(type default)
			)
			(layer "B.Fab")
		)
		(pad "1" smd rect
			(at 0.889 0 270)
			(size 1.016 1.27)
			(layers "B.Cu" "B.Mask" "B.Paste")
			(net "PVDDCR_CPU1_P1")
		)
		(pad "2" smd rect
			(at -0.889 0 270)
			(size 1.016 1.27)
			(layers "B.Cu" "B.Mask" "B.Paste")
			(net "GND")
		)
	)
)
